(kicad_pcb
	(version 20260206)
	(generator "pcbnew")
	(generator_version "10.0")
	(general
		(thickness 1.6)
		(legacy_teardrops no)
	)
	(paper "A4")
	(title_block
		(title "Wiwynn_Tioga_Pass_MB.brd")
		(comment 1 "Tioga Pass / footprint 3283 of 4770 (J6T1), pads 1-123 of 291")
	)
	(layers
		(0 "F.Cu" signal "TOP")
		(4 "In1.Cu" signal "L2GND")
		(6 "In2.Cu" signal "L3")
		(8 "In3.Cu" signal "L4GND")
		(10 "In4.Cu" signal "L5")
		(12 "In5.Cu" signal "L6GND")
		(14 "In6.Cu" signal "L7VCC")
		(16 "In7.Cu" signal "L8VCC")
		(18 "In8.Cu" signal "L9GND")
		(20 "In9.Cu" signal "L10")
		(22 "In10.Cu" signal "L11GND")
		(24 "In11.Cu" signal "L12")
		(26 "In12.Cu" signal "L13GND")
		(2 "B.Cu" signal "BOTTOM")
		(9 "F.Adhes" user "F.Adhesive")
		(11 "B.Adhes" user "B.Adhesive")
		(13 "F.Paste" user "Package Geometry/Pastemask Top")
		(15 "B.Paste" user "Package Geometry/Pastemask Bottom")
		(5 "F.SilkS" user "Ref Des/Silkscreen Top")
		(7 "B.SilkS" user "Ref Des/Silkscreen Bottom")
		(1 "F.Mask" user "Board Geometry/Soldermask Top")
		(3 "B.Mask" user "Board Geometry/Soldermask Bottom")
		(17 "Dwgs.User" user "User.Drawings")
		(19 "Cmts.User" user "User.Comments")
		(21 "Eco1.User" user "User.Eco1")
		(23 "Eco2.User" user "User.Eco2")
		(25 "Edge.Cuts" user "Board Geometry/Outline")
		(27 "Margin" user)
		(31 "F.CrtYd" user "Package Geometry/Place Bound Top")
		(29 "B.CrtYd" user "Package Geometry/Place Bound Bottom")
		(35 "F.Fab" user "Ref Des/Assembly Top")
		(33 "B.Fab" user "Ref Des/Assembly Bottom")
	)
	(footprint ""
		(layer "B.Cu")
		(at 194.700398 -24.824182 90)
		(property "Reference" "J6T1"
			(at 2.200148 39.23411 0)
			(unlocked yes)
			(layer "B.SilkS")
			(effects
				(font
					(size 0.7874 0.5842)
					(thickness 0.1524)
				)
				(justify left mirror)
			)
		)
		(property "Value" ""
			(at 0 0 90)
			(layer "B.Fab")
			(effects
				(font
					(size 1.27 1.27)
				)
				(justify mirror)
			)
		)
		(duplicate_pad_numbers_are_jumpers no)
		(pad "" thru_hole circle
			(at -2.29997 -5.649976 270)
			(size 2.8194 2.8194)
			(drill 2.4384)
			(layers "*.Cu" "*.Mask")
			(remove_unused_layers no)
			(clearance 0.127)
			(thermal_gap 0.127)
		)
		(pad "" thru_hole oval
			(at -2.29997 68.90004 270)
			(size 2.8194 1.5748)
			(drill oval 2.4384 1.1938)
			(layers "*.Cu" "*.Mask")
			(remove_unused_layers no)
			(clearance 0.127)
			(thermal_gap 0.127)
		)
		(pad "" thru_hole circle
			(at -2.29997 132.299964 270)
			(size 2.8194 2.8194)
			(drill 2.4384)
			(layers "*.Cu" "*.Mask")
			(remove_unused_layers no)
			(clearance 0.127)
			(thermal_gap 0.127)
		)
		(pad "1" smd rect
			(at 0 0 270)
			(size 1.8034 0.508)
			(layers "B.Cu" "B.Mask" "B.Paste")
			(net "P12V_NVDIMM_ABC")
		)
		(pad "2" smd rect
			(at 0 0.849884 270)
			(size 1.8034 0.508)
			(layers "B.Cu" "B.Mask" "B.Paste")
			(net "GND")
		)
		(pad "3" smd rect
			(at 0 1.700022 270)
			(size 1.8034 0.508)
			(layers "B.Cu" "B.Mask" "B.Paste")
			(net "M_A_DQ<4>")
		)
		(pad "4" smd rect
			(at 0 2.549906 270)
			(size 1.8034 0.508)
			(layers "B.Cu" "B.Mask" "B.Paste")
			(net "GND")
		)
		(pad "5" smd rect
			(at 0 3.400044 270)
			(size 1.8034 0.508)
			(layers "B.Cu" "B.Mask" "B.Paste")
			(net "M_A_DQ<0>")
		)
		(pad "6" smd rect
			(at 0 4.249928 270)
			(size 1.8034 0.508)
			(layers "B.Cu" "B.Mask" "B.Paste")
			(net "GND")
		)
		(pad "7" smd rect
			(at 0 5.100066 270)
			(size 1.8034 0.508)
			(layers "B.Cu" "B.Mask" "B.Paste")
			(net "M_A_DQS_DP<9>")
		)
		(pad "8" smd rect
			(at 0 5.94995 270)
			(size 1.8034 0.508)
			(layers "B.Cu" "B.Mask" "B.Paste")
			(net "M_A_DQS_DN<9>")
		)
		(pad "9" smd rect
			(at 0 6.800088 270)
			(size 1.8034 0.508)
			(layers "B.Cu" "B.Mask" "B.Paste")
			(net "GND")
		)
		(pad "10" smd rect
			(at 0 7.649972 270)
			(size 1.8034 0.508)
			(layers "B.Cu" "B.Mask" "B.Paste")
			(net "M_A_DQ<6>")
		)
		(pad "11" smd rect
			(at 0 8.50011 270)
			(size 1.8034 0.508)
			(layers "B.Cu" "B.Mask" "B.Paste")
			(net "GND")
		)
		(pad "12" smd rect
			(at 0 9.349994 270)
			(size 1.8034 0.508)
			(layers "B.Cu" "B.Mask" "B.Paste")
			(net "M_A_DQ<2>")
		)
		(pad "13" smd rect
			(at 0 10.199878 270)
			(size 1.8034 0.508)
			(layers "B.Cu" "B.Mask" "B.Paste")
			(net "GND")
		)
		(pad "14" smd rect
			(at 0 11.050016 270)
			(size 1.8034 0.508)
			(layers "B.Cu" "B.Mask" "B.Paste")
			(net "M_A_DQ<12>")
		)
		(pad "15" smd rect
			(at 0 11.8999 270)
			(size 1.8034 0.508)
			(layers "B.Cu" "B.Mask" "B.Paste")
			(net "GND")
		)
		(pad "16" smd rect
			(at 0 12.750038 270)
			(size 1.8034 0.508)
			(layers "B.Cu" "B.Mask" "B.Paste")
			(net "M_A_DQ<8>")
		)
		(pad "17" smd rect
			(at 0 13.599922 270)
			(size 1.8034 0.508)
			(layers "B.Cu" "B.Mask" "B.Paste")
			(net "GND")
		)
		(pad "18" smd rect
			(at 0 14.45006 270)
			(size 1.8034 0.508)
			(layers "B.Cu" "B.Mask" "B.Paste")
			(net "M_A_DQS_DP<10>")
		)
		(pad "19" smd rect
			(at 0 15.299944 270)
			(size 1.8034 0.508)
			(layers "B.Cu" "B.Mask" "B.Paste")
			(net "M_A_DQS_DN<10>")
		)
		(pad "20" smd rect
			(at 0 16.150082 270)
			(size 1.8034 0.508)
			(layers "B.Cu" "B.Mask" "B.Paste")
			(net "GND")
		)
		(pad "21" smd rect
			(at 0 16.999966 270)
			(size 1.8034 0.508)
			(layers "B.Cu" "B.Mask" "B.Paste")
			(net "M_A_DQ<14>")
		)
		(pad "22" smd rect
			(at 0 17.850104 270)
			(size 1.8034 0.508)
			(layers "B.Cu" "B.Mask" "B.Paste")
			(net "GND")
		)
		(pad "23" smd rect
			(at 0 18.699988 270)
			(size 1.8034 0.508)
			(layers "B.Cu" "B.Mask" "B.Paste")
			(net "M_A_DQ<10>")
		)
		(pad "24" smd rect
			(at 0 19.550126 270)
			(size 1.8034 0.508)
			(layers "B.Cu" "B.Mask" "B.Paste")
			(net "GND")
		)
		(pad "25" smd rect
			(at 0 20.40001 270)
			(size 1.8034 0.508)
			(layers "B.Cu" "B.Mask" "B.Paste")
			(net "M_A_DQ<20>")
		)
		(pad "26" smd rect
			(at 0 21.249894 270)
			(size 1.8034 0.508)
			(layers "B.Cu" "B.Mask" "B.Paste")
			(net "GND")
		)
		(pad "27" smd rect
			(at 0 22.100032 270)
			(size 1.8034 0.508)
			(layers "B.Cu" "B.Mask" "B.Paste")
			(net "M_A_DQ<16>")
		)
		(pad "28" smd rect
			(at 0 22.949916 270)
			(size 1.8034 0.508)
			(layers "B.Cu" "B.Mask" "B.Paste")
			(net "GND")
		)
		(pad "29" smd rect
			(at 0 23.800054 270)
			(size 1.8034 0.508)
			(layers "B.Cu" "B.Mask" "B.Paste")
			(net "M_A_DQS_DP<11>")
		)
		(pad "30" smd rect
			(at 0 24.649938 270)
			(size 1.8034 0.508)
			(layers "B.Cu" "B.Mask" "B.Paste")
			(net "M_A_DQS_DN<11>")
		)
		(pad "31" smd rect
			(at 0 25.500076 270)
			(size 1.8034 0.508)
			(layers "B.Cu" "B.Mask" "B.Paste")
			(net "GND")
		)
		(pad "32" smd rect
			(at 0 26.34996 270)
			(size 1.8034 0.508)
			(layers "B.Cu" "B.Mask" "B.Paste")
			(net "M_A_DQ<22>")
		)
		(pad "33" smd rect
			(at 0 27.200098 270)
			(size 1.8034 0.508)
			(layers "B.Cu" "B.Mask" "B.Paste")
			(net "GND")
		)
		(pad "34" smd rect
			(at 0 28.049982 270)
			(size 1.8034 0.508)
			(layers "B.Cu" "B.Mask" "B.Paste")
			(net "M_A_DQ<18>")
		)
		(pad "35" smd rect
			(at 0 28.90012 270)
			(size 1.8034 0.508)
			(layers "B.Cu" "B.Mask" "B.Paste")
			(net "GND")
		)
		(pad "36" smd rect
			(at 0 29.750004 270)
			(size 1.8034 0.508)
			(layers "B.Cu" "B.Mask" "B.Paste")
			(net "M_A_DQ<28>")
		)
		(pad "37" smd rect
			(at 0 30.599888 270)
			(size 1.8034 0.508)
			(layers "B.Cu" "B.Mask" "B.Paste")
			(net "GND")
		)
		(pad "38" smd rect
			(at 0 31.450026 270)
			(size 1.8034 0.508)
			(layers "B.Cu" "B.Mask" "B.Paste")
			(net "M_A_DQ<24>")
		)
		(pad "39" smd rect
			(at 0 32.29991 270)
			(size 1.8034 0.508)
			(layers "B.Cu" "B.Mask" "B.Paste")
			(net "GND")
		)
		(pad "40" smd rect
			(at 0 33.150048 270)
			(size 1.8034 0.508)
			(layers "B.Cu" "B.Mask" "B.Paste")
			(net "M_A_DQS_DP<12>")
		)
		(pad "41" smd rect
			(at 0 33.999932 270)
			(size 1.8034 0.508)
			(layers "B.Cu" "B.Mask" "B.Paste")
			(net "M_A_DQS_DN<12>")
		)
		(pad "42" smd rect
			(at 0 34.85007 270)
			(size 1.8034 0.508)
			(layers "B.Cu" "B.Mask" "B.Paste")
			(net "GND")
		)
		(pad "43" smd rect
			(at 0 35.699954 270)
			(size 1.8034 0.508)
			(layers "B.Cu" "B.Mask" "B.Paste")
			(net "M_A_DQ<30>")
		)
		(pad "44" smd rect
			(at 0 36.550092 270)
			(size 1.8034 0.508)
			(layers "B.Cu" "B.Mask" "B.Paste")
			(net "GND")
		)
		(pad "45" smd rect
			(at 0 37.399976 270)
			(size 1.8034 0.508)
			(layers "B.Cu" "B.Mask" "B.Paste")
			(net "M_A_DQ<26>")
		)
		(pad "46" smd rect
			(at 0 38.250114 270)
			(size 1.8034 0.508)
			(layers "B.Cu" "B.Mask" "B.Paste")
			(net "GND")
		)
		(pad "47" smd rect
			(at 0 39.099998 270)
			(size 1.8034 0.508)
			(layers "B.Cu" "B.Mask" "B.Paste")
			(net "M_A_ECC<4>")
		)
		(pad "48" smd rect
			(at 0 39.949882 270)
			(size 1.8034 0.508)
			(layers "B.Cu" "B.Mask" "B.Paste")
			(net "GND")
		)
		(pad "49" smd rect
			(at 0 40.80002 270)
			(size 1.8034 0.508)
			(layers "B.Cu" "B.Mask" "B.Paste")
			(net "M_A_ECC<0>")
		)
		(pad "50" smd rect
			(at 0 41.649904 270)
			(size 1.8034 0.508)
			(layers "B.Cu" "B.Mask" "B.Paste")
			(net "GND")
		)
		(pad "51" smd rect
			(at 0 42.500042 270)
			(size 1.8034 0.508)
			(layers "B.Cu" "B.Mask" "B.Paste")
			(net "M_A_DQS_DP<17>")
		)
		(pad "52" smd rect
			(at 0 43.349926 270)
			(size 1.8034 0.508)
			(layers "B.Cu" "B.Mask" "B.Paste")
			(net "M_A_DQS_DN<17>")
		)
		(pad "53" smd rect
			(at 0 44.200064 270)
			(size 1.8034 0.508)
			(layers "B.Cu" "B.Mask" "B.Paste")
			(net "GND")
		)
		(pad "54" smd rect
			(at 0 45.049948 270)
			(size 1.8034 0.508)
			(layers "B.Cu" "B.Mask" "B.Paste")
			(net "M_A_ECC<6>")
		)
		(pad "55" smd rect
			(at 0 45.900086 270)
			(size 1.8034 0.508)
			(layers "B.Cu" "B.Mask" "B.Paste")
			(net "GND")
		)
		(pad "56" smd rect
			(at 0 46.74997 270)
			(size 1.8034 0.508)
			(layers "B.Cu" "B.Mask" "B.Paste")
			(net "M_A_ECC<2>")
		)
		(pad "57" smd rect
			(at 0 47.600108 270)
			(size 1.8034 0.508)
			(layers "B.Cu" "B.Mask" "B.Paste")
			(net "GND")
		)
		(pad "58" smd rect
			(at 0 48.449992 270)
			(size 1.8034 0.508)
			(layers "B.Cu" "B.Mask" "B.Paste")
			(net "M_ABC_RST_N")
		)
		(pad "59" smd rect
			(at 0 49.299876 270)
			(size 1.8034 0.508)
			(layers "B.Cu" "B.Mask" "B.Paste")
			(net "PVDDQ_ABC")
		)
		(pad "60" smd rect
			(at 0 50.150014 270)
			(size 1.8034 0.508)
			(layers "B.Cu" "B.Mask" "B.Paste")
			(net "M_A_CKE<2>")
		)
		(pad "61" smd rect
			(at 0 50.999898 270)
			(size 1.8034 0.508)
			(layers "B.Cu" "B.Mask" "B.Paste")
			(net "PVDDQ_ABC")
		)
		(pad "62" smd rect
			(at 0 51.850036 270)
			(size 1.8034 0.508)
			(layers "B.Cu" "B.Mask" "B.Paste")
			(net "M_A_ACT_N")
		)
		(pad "63" smd rect
			(at 0 52.69992 270)
			(size 1.8034 0.508)
			(layers "B.Cu" "B.Mask" "B.Paste")
			(net "M_A_BG<0>")
		)
		(pad "64" smd rect
			(at 0 53.550058 270)
			(size 1.8034 0.508)
			(layers "B.Cu" "B.Mask" "B.Paste")
			(net "PVDDQ_ABC")
		)
		(pad "65" smd rect
			(at 0 54.399942 270)
			(size 1.8034 0.508)
			(layers "B.Cu" "B.Mask" "B.Paste")
			(net "M_A_MA<12>")
		)
		(pad "66" smd rect
			(at 0 55.25008 270)
			(size 1.8034 0.508)
			(layers "B.Cu" "B.Mask" "B.Paste")
			(net "M_A_MA<9>")
		)
		(pad "67" smd rect
			(at 0 56.099964 270)
			(size 1.8034 0.508)
			(layers "B.Cu" "B.Mask" "B.Paste")
			(net "PVDDQ_ABC")
		)
		(pad "68" smd rect
			(at 0 56.950102 270)
			(size 1.8034 0.508)
			(layers "B.Cu" "B.Mask" "B.Paste")
			(net "M_A_MA<8>")
		)
		(pad "69" smd rect
			(at 0 57.799986 270)
			(size 1.8034 0.508)
			(layers "B.Cu" "B.Mask" "B.Paste")
			(net "M_A_MA<6>")
		)
		(pad "70" smd rect
			(at 0 58.650124 270)
			(size 1.8034 0.508)
			(layers "B.Cu" "B.Mask" "B.Paste")
			(net "PVDDQ_ABC")
		)
		(pad "71" smd rect
			(at 0 59.500008 270)
			(size 1.8034 0.508)
			(layers "B.Cu" "B.Mask" "B.Paste")
			(net "M_A_MA<3>")
		)
		(pad "72" smd rect
			(at 0 60.349892 270)
			(size 1.8034 0.508)
			(layers "B.Cu" "B.Mask" "B.Paste")
			(net "M_A_MA<1>")
		)
		(pad "73" smd rect
			(at 0 61.20003 270)
			(size 1.8034 0.508)
			(layers "B.Cu" "B.Mask" "B.Paste")
			(net "PVDDQ_ABC")
		)
		(pad "74" smd rect
			(at 0 62.049914 270)
			(size 1.8034 0.508)
			(layers "B.Cu" "B.Mask" "B.Paste")
			(net "M_A_CLK_DP<2>")
		)
		(pad "75" smd rect
			(at 0 62.900052 270)
			(size 1.8034 0.508)
			(layers "B.Cu" "B.Mask" "B.Paste")
			(net "M_A_CLK_DN<2>")
		)
		(pad "76" smd rect
			(at 0 63.749936 270)
			(size 1.8034 0.508)
			(layers "B.Cu" "B.Mask" "B.Paste")
			(net "PVDDQ_ABC")
		)
		(pad "77" smd rect
			(at 0 64.600074 270)
			(size 1.8034 0.508)
			(layers "B.Cu" "B.Mask" "B.Paste")
			(net "PVTT_ABC")
		)
		(pad "78" smd rect
			(at 0 70.550024 270)
			(size 1.8034 0.508)
			(layers "B.Cu" "B.Mask" "B.Paste")
			(net "FM_DIMM_EVENT_COD_N")
		)
		(pad "79" smd rect
			(at 0 71.399908 270)
			(size 1.8034 0.508)
			(layers "B.Cu" "B.Mask" "B.Paste")
			(net "M_A_MA<0>")
		)
		(pad "80" smd rect
			(at 0 72.250046 270)
			(size 1.8034 0.508)
			(layers "B.Cu" "B.Mask" "B.Paste")
			(net "PVDDQ_ABC")
		)
		(pad "81" smd rect
			(at 0 73.09993 270)
			(size 1.8034 0.508)
			(layers "B.Cu" "B.Mask" "B.Paste")
			(net "M_A_BA<0>")
		)
		(pad "82" smd rect
			(at 0 73.950068 270)
			(size 1.8034 0.508)
			(layers "B.Cu" "B.Mask" "B.Paste")
			(net "M_A_MA<16>")
		)
		(pad "83" smd rect
			(at 0 74.799952 270)
			(size 1.8034 0.508)
			(layers "B.Cu" "B.Mask" "B.Paste")
			(net "PVDDQ_ABC")
		)
		(pad "84" smd rect
			(at 0 75.65009 270)
			(size 1.8034 0.508)
			(layers "B.Cu" "B.Mask" "B.Paste")
			(net "M_A_CS_N<4>")
		)
		(pad "85" smd rect
			(at 0 76.499974 270)
			(size 1.8034 0.508)
			(layers "B.Cu" "B.Mask" "B.Paste")
			(net "PVDDQ_ABC")
		)
		(pad "86" smd rect
			(at 0 77.350112 270)
			(size 1.8034 0.508)
			(layers "B.Cu" "B.Mask" "B.Paste")
			(net "M_A_MA<15>")
		)
		(pad "87" smd rect
			(at 0 78.199996 270)
			(size 1.8034 0.508)
			(layers "B.Cu" "B.Mask" "B.Paste")
			(net "M_A_ODT<2>")
		)
		(pad "88" smd rect
			(at 0 79.04988 270)
			(size 1.8034 0.508)
			(layers "B.Cu" "B.Mask" "B.Paste")
			(net "PVDDQ_ABC")
		)
		(pad "89" smd rect
			(at 0 79.900018 270)
			(size 1.8034 0.508)
			(layers "B.Cu" "B.Mask" "B.Paste")
			(net "M_A_CS_N<5>")
		)
		(pad "90" smd rect
			(at 0 80.749902 270)
			(size 1.8034 0.508)
			(layers "B.Cu" "B.Mask" "B.Paste")
			(net "PVDDQ_ABC")
		)
		(pad "91" smd rect
			(at 0 81.60004 270)
			(size 1.8034 0.508)
			(layers "B.Cu" "B.Mask" "B.Paste")
			(net "M_A_ODT<3>")
		)
		(pad "92" smd rect
			(at 0 82.449924 270)
			(size 1.8034 0.508)
			(layers "B.Cu" "B.Mask" "B.Paste")
			(net "PVDDQ_ABC")
		)
		(pad "93" smd rect
			(at 0 83.300062 270)
			(size 1.8034 0.508)
			(layers "B.Cu" "B.Mask" "B.Paste")
			(net "M_A_CS_N<6>")
		)
		(pad "94" smd rect
			(at 0 84.149946 270)
			(size 1.8034 0.508)
			(layers "B.Cu" "B.Mask" "B.Paste")
			(net "GND")
		)
		(pad "95" smd rect
			(at 0 85.000084 270)
			(size 1.8034 0.508)
			(layers "B.Cu" "B.Mask" "B.Paste")
			(net "M_A_DQ<36>")
		)
		(pad "96" smd rect
			(at 0 85.849968 270)
			(size 1.8034 0.508)
			(layers "B.Cu" "B.Mask" "B.Paste")
			(net "GND")
		)
		(pad "97" smd rect
			(at 0 86.700106 270)
			(size 1.8034 0.508)
			(layers "B.Cu" "B.Mask" "B.Paste")
			(net "M_A_DQ<32>")
		)
		(pad "98" smd rect
			(at 0 87.54999 270)
			(size 1.8034 0.508)
			(layers "B.Cu" "B.Mask" "B.Paste")
			(net "GND")
		)
		(pad "99" smd rect
			(at 0 88.399874 270)
			(size 1.8034 0.508)
			(layers "B.Cu" "B.Mask" "B.Paste")
			(net "M_A_DQS_DP<13>")
		)
		(pad "100" smd rect
			(at 0 89.250012 270)
			(size 1.8034 0.508)
			(layers "B.Cu" "B.Mask" "B.Paste")
			(net "M_A_DQS_DN<13>")
		)
		(pad "101" smd rect
			(at 0 90.099896 270)
			(size 1.8034 0.508)
			(layers "B.Cu" "B.Mask" "B.Paste")
			(net "GND")
		)
		(pad "102" smd rect
			(at 0 90.950034 270)
			(size 1.8034 0.508)
			(layers "B.Cu" "B.Mask" "B.Paste")
			(net "M_A_DQ<38>")
		)
		(pad "103" smd rect
			(at 0 91.799918 270)
			(size 1.8034 0.508)
			(layers "B.Cu" "B.Mask" "B.Paste")
			(net "GND")
		)
		(pad "104" smd rect
			(at 0 92.650056 270)
			(size 1.8034 0.508)
			(layers "B.Cu" "B.Mask" "B.Paste")
			(net "M_A_DQ<34>")
		)
		(pad "105" smd rect
			(at 0 93.49994 270)
			(size 1.8034 0.508)
			(layers "B.Cu" "B.Mask" "B.Paste")
			(net "GND")
		)
		(pad "106" smd rect
			(at 0 94.350078 270)
			(size 1.8034 0.508)
			(layers "B.Cu" "B.Mask" "B.Paste")
			(net "M_A_DQ<44>")
		)
		(pad "107" smd rect
			(at 0 95.199962 270)
			(size 1.8034 0.508)
			(layers "B.Cu" "B.Mask" "B.Paste")
			(net "GND")
		)
		(pad "108" smd rect
			(at 0 96.0501 270)
			(size 1.8034 0.508)
			(layers "B.Cu" "B.Mask" "B.Paste")
			(net "M_A_DQ<40>")
		)
		(pad "109" smd rect
			(at 0 96.899984 270)
			(size 1.8034 0.508)
			(layers "B.Cu" "B.Mask" "B.Paste")
			(net "GND")
		)
		(pad "110" smd rect
			(at 0 97.750122 270)
			(size 1.8034 0.508)
			(layers "B.Cu" "B.Mask" "B.Paste")
			(net "M_A_DQS_DP<14>")
		)
		(pad "111" smd rect
			(at 0 98.600006 270)
			(size 1.8034 0.508)
			(layers "B.Cu" "B.Mask" "B.Paste")
			(net "M_A_DQS_DN<14>")
		)
		(pad "112" smd rect
			(at 0 99.44989 270)
			(size 1.8034 0.508)
			(layers "B.Cu" "B.Mask" "B.Paste")
			(net "GND")
		)
		(pad "113" smd rect
			(at 0 100.300028 270)
			(size 1.8034 0.508)
			(layers "B.Cu" "B.Mask" "B.Paste")
			(net "M_A_DQ<46>")
		)
		(pad "114" smd rect
			(at 0 101.149912 270)
			(size 1.8034 0.508)
			(layers "B.Cu" "B.Mask" "B.Paste")
			(net "GND")
		)
		(pad "115" smd rect
			(at 0 102.00005 270)
			(size 1.8034 0.508)
			(layers "B.Cu" "B.Mask" "B.Paste")
			(net "M_A_DQ<42>")
		)
		(pad "116" smd rect
			(at 0 102.849934 270)
			(size 1.8034 0.508)
			(layers "B.Cu" "B.Mask" "B.Paste")
			(net "GND")
		)
		(pad "117" smd rect
			(at 0 103.700072 270)
			(size 1.8034 0.508)
			(layers "B.Cu" "B.Mask" "B.Paste")
			(net "M_A_DQ<52>")
		)
		(pad "118" smd rect
			(at 0 104.549956 270)
			(size 1.8034 0.508)
			(layers "B.Cu" "B.Mask" "B.Paste")
			(net "GND")
		)
		(pad "119" smd rect
			(at 0 105.400094 270)
			(size 1.8034 0.508)
			(layers "B.Cu" "B.Mask" "B.Paste")
			(net "M_A_DQ<48>")
		)
		(pad "120" smd rect
			(at 0 106.249978 270)
			(size 1.8034 0.508)
			(layers "B.Cu" "B.Mask" "B.Paste")
			(net "GND")
		)
	)
)
